# T6G (Grand Teton) — schematic netlist excerpt (pin names and nets, part order shuffled) for the footprints in the layout excerpt that follows; sources: Cadence DE-HDL packaged netlist, KiCad conversion of 04192023_DAF0TMB3IC0_F0TG_MB_C_brd_V02_OCP.brd

R3164  Q_RES  10K 1% CHIP  pkg 0402LF  page 137 : A = GND ; B = OCP_V3_2_AUX_PWR_EN

(kicad_pcb
	(version 20260206)
	(generator "pcbnew")
	(generator_version "10.0")
	(general
		(thickness 1.6)
		(legacy_teardrops no)
	)
	(paper "A4")
	(title_block
		(title "04192023_DAF0TMB3IC0_F0TG_MB_C_brd_V02_OCP.brd")
		(comment 1 "Grand Teton / footprints 2695-2695 of 8354")
	)
	(layers
		(0 "F.Cu" signal "TOP")
		(4 "In1.Cu" signal "GND")
		(6 "In2.Cu" signal "IN1")
		(8 "In3.Cu" signal "GND1")
		(10 "In4.Cu" signal "IN2")
		(12 "In5.Cu" signal "GND2")
		(14 "In6.Cu" signal "IN3")
		(16 "In7.Cu" signal "GND3")
		(18 "In8.Cu" signal "VCC")
		(20 "In9.Cu" signal "VCC1")
		(22 "In10.Cu" signal "GND4")
		(24 "In11.Cu" signal "IN4")
		(26 "In12.Cu" signal "GND5")
		(28 "In13.Cu" signal "IN5")
		(30 "In14.Cu" signal "GND6")
		(32 "In15.Cu" signal "IN6")
		(34 "In16.Cu" signal "GND7")
		(2 "B.Cu" signal "BOTTOM")
		(9 "F.Adhes" user "F.Adhesive")
		(11 "B.Adhes" user "B.Adhesive")
		(13 "F.Paste" user "Package Geometry/Pastemask Top")
		(15 "B.Paste" user "Package Geometry/Pastemask Bottom")
		(5 "F.SilkS" user "Ref Des/Silkscreen Top")
		(7 "B.SilkS" user "Ref Des/Silkscreen Bottom")
		(1 "F.Mask" user "Board Geometry/Soldermask Top")
		(3 "B.Mask" user "Board Geometry/Soldermask Bottom")
		(17 "Dwgs.User" user "User.Drawings")
		(19 "Cmts.User" user "User.Comments")
		(21 "Eco1.User" user "User.Eco1")
		(23 "Eco2.User" user "User.Eco2")
		(25 "Edge.Cuts" user "Board Geometry/Outline")
		(27 "Margin" user)
		(31 "F.CrtYd" user "Package Geometry/Place Bound Top")
		(29 "B.CrtYd" user "Package Geometry/Place Bound Bottom")
		(35 "F.Fab" user "Ref Des/Assembly Top")
		(33 "B.Fab" user "Ref Des/Assembly Bottom")
	)
	(footprint ""
		(layer "F.Cu")
		(at 61.90488 -19.268948 180)
		(property "Reference" "R3164"
			(at 0 0 180)
			(layer "F.SilkS")
			(hide yes)
			(effects
				(font
					(size 1.27 1.27)
				)
			)
		)
		(property "Value" ""
			(at 0 0 180)
			(layer "F.Fab")
			(effects
				(font
					(size 1.27 1.27)
				)
			)
		)
		(duplicate_pad_numbers_are_jumpers no)
		(fp_line
			(start 0.7874 0.4064)
			(end -0.7874 0.4064)
			(stroke
				(width 0.1524)
				(type default)
			)
			(layer "F.SilkS")
		)
		(fp_line
			(start 0.7874 -0.4064)
			(end 0.7874 0.4064)
			(stroke
				(width 0.1524)
				(type default)
			)
			(layer "F.SilkS")
		)
		(fp_line
			(start -0.7874 0.4064)
			(end -0.7874 -0.4064)
			(stroke
				(width 0.1524)
				(type default)
			)
			(layer "F.SilkS")
		)
		(fp_line
			(start -0.7874 -0.4064)
			(end 0.7874 -0.4064)
			(stroke
				(width 0.1524)
				(type default)
			)
			(layer "F.SilkS")
		)
		(fp_line
			(start 0.67945 0.3048)
			(end 0.120396 0.3048)
			(stroke
				(width 0.1)
				(type default)
			)
			(layer "F.Fab")
		)
		(fp_line
			(start 0.67945 -0.3048)
			(end 0.67945 0.3048)
			(stroke
				(width 0.1)
				(type default)
			)
			(layer "F.Fab")
		)
		(fp_line
			(start 0.12065 -0.2794)
			(end 0.12065 -0.3048)
			(stroke
				(width 0.1)
				(type default)
			)
			(layer "F.Fab")
		)
		(fp_line
			(start 0.12065 -0.3048)
			(end 0.67945 -0.3048)
			(stroke
				(width 0.1)
				(type default)
			)
			(layer "F.Fab")
		)
		(fp_line
			(start 0.120396 0.3048)
			(end 0.120396 0.2794)
			(stroke
				(width 0.1)
				(type default)
			)
			(layer "F.Fab")
		)
		(fp_line
			(start 0.120396 0.2794)
			(end -0.12065 0.2794)
			(stroke
				(width 0.1)
				(type default)
			)
			(layer "F.Fab")
		)
		(fp_line
			(start -0.12065 0.3048)
			(end -0.67945 0.3048)
			(stroke
				(width 0.1)
				(type default)
			)
			(layer "F.Fab")
		)
		(fp_line
			(start -0.12065 0.2794)
			(end -0.12065 0.3048)
			(stroke
				(width 0.1)
				(type default)
			)
			(layer "F.Fab")
		)
		(fp_line
			(start -0.12065 -0.2794)
			(end 0.12065 -0.2794)
			(stroke
				(width 0.1)
				(type default)
			)
			(layer "F.Fab")
		)
		(fp_line
			(start -0.12065 -0.305054)
			(end -0.12065 -0.2794)
			(stroke
				(width 0.1)
				(type default)
			)
			(layer "F.Fab")
		)
		(fp_line
			(start -0.67945 0.3048)
			(end -0.67945 -0.305054)
			(stroke
				(width 0.1)
				(type default)
			)
			(layer "F.Fab")
		)
		(fp_line
			(start -0.67945 -0.305054)
			(end -0.12065 -0.305054)
			(stroke
				(width 0.1)
				(type default)
			)
			(layer "F.Fab")
		)
		(pad "1" smd circle
			(at -0.40005 0 180)
			(size 0 0)
			(layers "F.Cu" "F.Mask" "F.Paste")
			(net "GND")
		)
		(pad "2" smd circle
			(at 0.40005 0 180)
			(size 0 0)
			(layers "F.Cu" "F.Mask" "F.Paste")
			(net "OCP_V3_2_AUX_PWR_EN")
		)
	)
)
